(kicad_pcb
	(version 20221018)
	(generator pcbnew)
	(general
    (thickness 1.518)
  )
	(paper "A4")
	(title_block
    (title "Kria K26 Devboard")
    (date "2024-03-26")
    (rev "1.2.5")
    (comment 1 "www.antmicro.com")
    (comment 2 "Antmicro Ltd.")
		(comment 9 "footprints 459-468 of 660")
	)
	(layers
    (0 "F.Cu" mixed)
    (1 "In1.Cu" power)
    (2 "In2.Cu" mixed)
    (3 "In3.Cu" power)
    (4 "In4.Cu" mixed)
    (5 "In5.Cu" power)
    (6 "In6.Cu" mixed)
    (31 "B.Cu" power)
    (32 "B.Adhes" user "B.Adhesive")
    (33 "F.Adhes" user "F.Adhesive")
    (34 "B.Paste" user)
    (35 "F.Paste" user)
    (36 "B.SilkS" user "B.Silkscreen")
    (37 "F.SilkS" user "F.Silkscreen")
    (38 "B.Mask" user)
    (39 "F.Mask" user)
    (40 "Dwgs.User" user "User.Drawings")
    (41 "Cmts.User" user "User.Comments")
    (42 "Eco1.User" user "User.Eco1")
    (43 "Eco2.User" user "User.Eco2")
    (44 "Edge.Cuts" user)
    (45 "Margin" user)
    (46 "B.CrtYd" user "B.Courtyard")
    (47 "F.CrtYd" user "F.Courtyard")
    (48 "B.Fab" user)
    (49 "F.Fab" user)
  )
	(footprint "kria-k26-devboard-footprints:C_0402_1005Metric" (layer "B.Cu")
    (at 105.75 133.9 -90)
    (descr "Capacitor SMD 0402")
    (tags "capacitor SMD 0402")
    (property "Author" "Antmicro")
    (property "Dielectric" "X5R")
    (property "License" "Apache-2.0")
    (property "MPN" "GRM155R61H104KE14D")
    (property "Manufacturer" "Murata")
    (property "Sheetfile" "i2c.kicad_sch")
    (property "Sheetname" "I2C ")
    (property "Val" "100n")
    (property "Voltage" "50V")
    (property "ki_description" " ")
    (attr smd)
    (fp_text reference "C34" (at 0.85 -0.35 90) (layer "B.SilkS")
        (effects (font (size 0.7 0.7) (thickness 0.15)) (justify left bottom mirror))
    )
    (fp_text value "C_100n_0402" (at 0 -1.4 90) (layer "B.Fab") hide
        (effects (font (size 0.7 0.7) (thickness 0.15)) (justify left bottom mirror))
    )
    (fp_text user "License: Apache-2.0" (at -0.932 -5.17 90) (layer "B.Fab") hide
        (effects (font (size 0.7 0.7) (thickness 0.15)) (justify left bottom mirror))
    )
    (fp_text user "${REFERENCE}" (at -0.932 -3.168 90) (layer "B.Fab") hide
        (effects (font (size 0.7 0.7) (thickness 0.15)) (justify left bottom mirror))
    )
    (fp_text user "Author: Antmicro" (at -0.932 -4.17 90) (layer "B.Fab") hide
        (effects (font (size 0.7 0.7) (thickness 0.15)) (justify left bottom mirror))
    )
    (fp_rect (start -0.94 0.47) (end 0.94 -0.47)
      (stroke (width 0.05) (type solid)) (fill none) (layer "B.CrtYd"))
    (fp_rect (start -0.499 0.249) (end 0.499 -0.249)
      (stroke (width 0.15) (type solid)) (fill none) (layer "B.Fab"))
    (pad "1" smd roundrect (at -0.484 0 270) (size 0.59 0.64) (layers "B.Cu" "B.Paste" "B.Mask") (roundrect_rratio 0.25)
      (net 15 "PS_3V3") (pintype "passive"))
    (pad "2" smd roundrect (at 0.484 0 270) (size 0.59 0.64) (layers "B.Cu" "B.Paste" "B.Mask") (roundrect_rratio 0.25)
      (net 1 "GND") (pintype "passive"))
  )
	(footprint "kria-k26-devboard-footprints:R_0402_1005Metric" (layer "B.Cu")
    (at 101.84 135.29)
    (descr "Resistor SMD 0402")
    (tags "resistor SMD 0402")
    (property "Author" "Antmicro")
    (property "License" "Apache-2.0")
    (property "MPN" "CR0402-FX-2201GLF")
    (property "Manufacturer" "Bourns")
    (property "Sheetfile" "i2c.kicad_sch")
    (property "Sheetname" "I2C ")
    (property "Tolerance" "1%")
    (property "Val" "2k2")
    (property "ki_description" "2k2 resistor in 0402 package with 1% tolerance")
    (attr smd)
    (fp_text reference "R34" (at -0.85 0.52 180) (layer "B.SilkS")
        (effects (font (size 0.7 0.7) (thickness 0.15)) (justify left bottom mirror))
    )
    (fp_text value "R_2k2_0402" (at 0 -1.4 180) (layer "B.Fab") hide
        (effects (font (size 0.7 0.7) (thickness 0.15)) (justify left bottom mirror))
    )
    (fp_text user "License: Apache-2.0" (at -0.95 -5.169 180) (layer "B.Fab") hide
        (effects (font (size 0.7 0.7) (thickness 0.15)) (justify left bottom mirror))
    )
    (fp_text user "Author: Antmicro" (at -0.95 -4.169 180) (layer "B.Fab") hide
        (effects (font (size 0.7 0.7) (thickness 0.15)) (justify left bottom mirror))
    )
    (fp_text user "${REFERENCE}" (at -0.95 -3.168 180) (layer "B.Fab") hide
        (effects (font (size 0.7 0.7) (thickness 0.15)) (justify left bottom mirror))
    )
    (fp_rect (start -0.93 0.47) (end 0.93 -0.47)
      (stroke (width 0.05) (type solid)) (fill none) (layer "B.CrtYd"))
    (fp_rect (start -0.5 0.25) (end 0.5 -0.25)
      (stroke (width 0.15) (type solid)) (fill none) (layer "B.Fab"))
    (pad "1" smd roundrect (at -0.485 0) (size 0.59 0.64) (layers "B.Cu" "B.Paste" "B.Mask") (roundrect_rratio 0.25)
      (net 15 "PS_3V3") (pintype "passive"))
    (pad "2" smd roundrect (at 0.485 0) (size 0.59 0.64) (layers "B.Cu" "B.Paste" "B.Mask") (roundrect_rratio 0.25)
      (net 162 "/I2C /I2C_SCK_3V3") (pintype "passive"))
  )
	(footprint "kria-k26-devboard-footprints:R_0402_1005Metric" (layer "B.Cu")
    (at 101.84 133.39)
    (descr "Resistor SMD 0402")
    (tags "resistor SMD 0402")
    (property "Author" "Antmicro")
    (property "License" "Apache-2.0")
    (property "MPN" "CR0402-FX-2003GLF")
    (property "Manufacturer" "Bourns")
    (property "Sheetfile" "i2c.kicad_sch")
    (property "Sheetname" "I2C ")
    (property "Tolerance" "1%")
    (property "Val" "200k")
    (property "ki_description" "200k resistor in 0402 package with 1% tolerance")
    (attr smd)
    (fp_text reference "R33" (at -0.87 0.49 180) (layer "B.SilkS")
        (effects (font (size 0.7 0.7) (thickness 0.15)) (justify left bottom mirror))
    )
    (fp_text value "R_200k_0402" (at 0 -1.4 180) (layer "B.Fab") hide
        (effects (font (size 0.7 0.7) (thickness 0.15)) (justify left bottom mirror))
    )
    (fp_text user "License: Apache-2.0" (at -0.95 -5.169 180) (layer "B.Fab") hide
        (effects (font (size 0.7 0.7) (thickness 0.15)) (justify left bottom mirror))
    )
    (fp_text user "Author: Antmicro" (at -0.95 -4.169 180) (layer "B.Fab") hide
        (effects (font (size 0.7 0.7) (thickness 0.15)) (justify left bottom mirror))
    )
    (fp_text user "${REFERENCE}" (at -0.95 -3.168 180) (layer "B.Fab") hide
        (effects (font (size 0.7 0.7) (thickness 0.15)) (justify left bottom mirror))
    )
    (fp_rect (start -0.93 0.47) (end 0.93 -0.47)
      (stroke (width 0.05) (type solid)) (fill none) (layer "B.CrtYd"))
    (fp_rect (start -0.5 0.25) (end 0.5 -0.25)
      (stroke (width 0.15) (type solid)) (fill none) (layer "B.Fab"))
    (pad "1" smd roundrect (at -0.485 0) (size 0.59 0.64) (layers "B.Cu" "B.Paste" "B.Mask") (roundrect_rratio 0.25)
      (net 15 "PS_3V3") (pintype "passive"))
    (pad "2" smd roundrect (at 0.485 0) (size 0.59 0.64) (layers "B.Cu" "B.Paste" "B.Mask") (roundrect_rratio 0.25)
      (net 324 "/I2C /Vref2") (pintype "passive"))
  )
	(footprint "kria-k26-devboard-footprints:C_0402_1005Metric" (layer "B.Cu")
    (at 101.84 134.34 180)
    (descr "Capacitor SMD 0402")
    (tags "capacitor SMD 0402")
    (property "Author" "Antmicro")
    (property "Dielectric" "C0G")
    (property "License" "Apache-2.0")
    (property "MPN" "GCM1555C1H101JA16D")
    (property "Manufacturer" "Murata")
    (property "Sheetfile" "i2c.kicad_sch")
    (property "Sheetname" "I2C ")
    (property "Val" "100p")
    (property "Voltage" "50V")
    (property "ki_description" " ")
    (attr smd)
    (fp_text reference "C33" (at 0.86 -0.49) (layer "B.SilkS")
        (effects (font (size 0.7 0.7) (thickness 0.15)) (justify left bottom mirror))
    )
    (fp_text value "C_100p_0402" (at 0 -1.4) (layer "B.Fab") hide
        (effects (font (size 0.7 0.7) (thickness 0.15)) (justify left bottom mirror))
    )
    (fp_text user "License: Apache-2.0" (at -0.932 -5.17) (layer "B.Fab") hide
        (effects (font (size 0.7 0.7) (thickness 0.15)) (justify left bottom mirror))
    )
    (fp_text user "Author: Antmicro" (at -0.932 -4.17) (layer "B.Fab") hide
        (effects (font (size 0.7 0.7) (thickness 0.15)) (justify left bottom mirror))
    )
    (fp_text user "${REFERENCE}" (at -0.932 -3.168) (layer "B.Fab") hide
        (effects (font (size 0.7 0.7) (thickness 0.15)) (justify left bottom mirror))
    )
    (fp_rect (start -0.94 0.47) (end 0.94 -0.47)
      (stroke (width 0.05) (type solid)) (fill none) (layer "B.CrtYd"))
    (fp_rect (start -0.499 0.249) (end 0.499 -0.249)
      (stroke (width 0.15) (type solid)) (fill none) (layer "B.Fab"))
    (pad "1" smd roundrect (at -0.484 0 180) (size 0.59 0.64) (layers "B.Cu" "B.Paste" "B.Mask") (roundrect_rratio 0.25)
      (net 324 "/I2C /Vref2") (pintype "passive"))
    (pad "2" smd roundrect (at 0.484 0 180) (size 0.59 0.64) (layers "B.Cu" "B.Paste" "B.Mask") (roundrect_rratio 0.25)
      (net 1 "GND") (pintype "passive"))
  )
	(footprint "kria-k26-devboard-footprints:R_0402_1005Metric" (layer "B.Cu")
    (at 101.84 136.24)
    (descr "Resistor SMD 0402")
    (tags "resistor SMD 0402")
    (property "Author" "Antmicro")
    (property "License" "Apache-2.0")
    (property "MPN" "CR0402-FX-2201GLF")
    (property "Manufacturer" "Bourns")
    (property "Sheetfile" "i2c.kicad_sch")
    (property "Sheetname" "I2C ")
    (property "Tolerance" "1%")
    (property "Val" "2k2")
    (property "ki_description" "2k2 resistor in 0402 package with 1% tolerance")
    (attr smd)
    (fp_text reference "R35" (at -0.85 0.56 180) (layer "B.SilkS")
        (effects (font (size 0.7 0.7) (thickness 0.15)) (justify left bottom mirror))
    )
    (fp_text value "R_2k2_0402" (at 0 -1.4 180) (layer "B.Fab") hide
        (effects (font (size 0.7 0.7) (thickness 0.15)) (justify left bottom mirror))
    )
    (fp_text user "Author: Antmicro" (at -0.95 -4.169 180) (layer "B.Fab") hide
        (effects (font (size 0.7 0.7) (thickness 0.15)) (justify left bottom mirror))
    )
    (fp_text user "License: Apache-2.0" (at -0.95 -5.169 180) (layer "B.Fab") hide
        (effects (font (size 0.7 0.7) (thickness 0.15)) (justify left bottom mirror))
    )
    (fp_text user "${REFERENCE}" (at -0.95 -3.168 180) (layer "B.Fab") hide
        (effects (font (size 0.7 0.7) (thickness 0.15)) (justify left bottom mirror))
    )
    (fp_rect (start -0.93 0.47) (end 0.93 -0.47)
      (stroke (width 0.05) (type solid)) (fill none) (layer "B.CrtYd"))
    (fp_rect (start -0.5 0.25) (end 0.5 -0.25)
      (stroke (width 0.15) (type solid)) (fill none) (layer "B.Fab"))
    (pad "1" smd roundrect (at -0.485 0) (size 0.59 0.64) (layers "B.Cu" "B.Paste" "B.Mask") (roundrect_rratio 0.25)
      (net 15 "PS_3V3") (pintype "passive"))
    (pad "2" smd roundrect (at 0.485 0) (size 0.59 0.64) (layers "B.Cu" "B.Paste" "B.Mask") (roundrect_rratio 0.25)
      (net 163 "/I2C /I2C_SDA_3V3") (pintype "passive"))
  )
	(footprint "kria-k26-devboard-footprints:C_0402_1005Metric" (layer "B.Cu")
    (at 116.556942 86.4)
    (descr "Capacitor SMD 0402")
    (tags "capacitor SMD 0402")
    (property "Author" "Antmicro")
    (property "Dielectric" "X5R")
    (property "License" "Apache-2.0")
    (property "MPN" "GRM155R61H104KE14D")
    (property "Manufacturer" "Murata")
    (property "Sheetfile" "usb.kicad_sch")
    (property "Sheetname" "USB")
    (property "Val" "100n")
    (property "Voltage" "50V")
    (property "ki_description" " ")
    (attr smd)
    (fp_text reference "C43" (at -0.896942 0.38 180) (layer "B.SilkS")
        (effects (font (size 0.7 0.7) (thickness 0.15)) (justify left bottom mirror))
    )
    (fp_text value "C_100n_0402" (at 0 -1.4 180) (layer "B.Fab") hide
        (effects (font (size 0.7 0.7) (thickness 0.15)) (justify left bottom mirror))
    )
    (fp_text user "License: Apache-2.0" (at -0.932 -5.17 180) (layer "B.Fab") hide
        (effects (font (size 0.7 0.7) (thickness 0.15)) (justify left bottom mirror))
    )
    (fp_text user "Author: Antmicro" (at -0.932 -4.17 180) (layer "B.Fab") hide
        (effects (font (size 0.7 0.7) (thickness 0.15)) (justify left bottom mirror))
    )
    (fp_text user "${REFERENCE}" (at -0.932 -3.168 180) (layer "B.Fab") hide
        (effects (font (size 0.7 0.7) (thickness 0.15)) (justify left bottom mirror))
    )
    (fp_rect (start -0.94 0.47) (end 0.94 -0.47)
      (stroke (width 0.05) (type solid)) (fill none) (layer "B.CrtYd"))
    (fp_rect (start -0.499 0.249) (end 0.499 -0.249)
      (stroke (width 0.15) (type solid)) (fill none) (layer "B.Fab"))
    (pad "1" smd roundrect (at -0.484 0) (size 0.59 0.64) (layers "B.Cu" "B.Paste" "B.Mask") (roundrect_rratio 0.25)
      (net 15 "PS_3V3") (pintype "passive"))
    (pad "2" smd roundrect (at 0.484 0) (size 0.59 0.64) (layers "B.Cu" "B.Paste" "B.Mask") (roundrect_rratio 0.25)
      (net 1 "GND") (pintype "passive"))
  )
	(footprint "kria-k26-devboard-footprints:C_0402_1005Metric" (layer "B.Cu")
    (at 121.7 90 90)
    (descr "Capacitor SMD 0402")
    (tags "capacitor SMD 0402")
    (property "Author" "Antmicro")
    (property "Dielectric" "X5R")
    (property "License" "Apache-2.0")
    (property "MPN" "GRM155R61H104KE14D")
    (property "Manufacturer" "Murata")
    (property "Sheetfile" "usb.kicad_sch")
    (property "Sheetname" "USB")
    (property "Val" "100n")
    (property "Voltage" "50V")
    (property "ki_description" " ")
    (attr smd)
    (fp_text reference "C51" (at -0.84 0.39 270) (layer "B.SilkS")
        (effects (font (size 0.7 0.7) (thickness 0.15)) (justify left bottom mirror))
    )
    (fp_text value "C_100n_0402" (at 0 -1.4 270) (layer "B.Fab") hide
        (effects (font (size 0.7 0.7) (thickness 0.15)) (justify left bottom mirror))
    )
    (fp_text user "License: Apache-2.0" (at -0.932 -5.17 270) (layer "B.Fab") hide
        (effects (font (size 0.7 0.7) (thickness 0.15)) (justify left bottom mirror))
    )
    (fp_text user "${REFERENCE}" (at -0.932 -3.168 270) (layer "B.Fab") hide
        (effects (font (size 0.7 0.7) (thickness 0.15)) (justify left bottom mirror))
    )
    (fp_text user "Author: Antmicro" (at -0.932 -4.17 270) (layer "B.Fab") hide
        (effects (font (size 0.7 0.7) (thickness 0.15)) (justify left bottom mirror))
    )
    (fp_rect (start -0.94 0.47) (end 0.94 -0.47)
      (stroke (width 0.05) (type solid)) (fill none) (layer "B.CrtYd"))
    (fp_rect (start -0.499 0.249) (end 0.499 -0.249)
      (stroke (width 0.15) (type solid)) (fill none) (layer "B.Fab"))
    (pad "1" smd roundrect (at -0.484 0 90) (size 0.59 0.64) (layers "B.Cu" "B.Paste" "B.Mask") (roundrect_rratio 0.25)
      (net 15 "PS_3V3") (pintype "passive"))
    (pad "2" smd roundrect (at 0.484 0 90) (size 0.59 0.64) (layers "B.Cu" "B.Paste" "B.Mask") (roundrect_rratio 0.25)
      (net 1 "GND") (pintype "passive"))
  )
	(footprint "kria-k26-devboard-footprints:C_0402_1005Metric" (layer "B.Cu")
    (at 126.4 90 90)
    (descr "Capacitor SMD 0402")
    (tags "capacitor SMD 0402")
    (property "Author" "Antmicro")
    (property "Dielectric" "X5R")
    (property "License" "Apache-2.0")
    (property "MPN" "GRM155R61H104KE14D")
    (property "Manufacturer" "Murata")
    (property "Sheetfile" "usb.kicad_sch")
    (property "Sheetname" "USB")
    (property "Val" "100n")
    (property "Voltage" "50V")
    (property "ki_description" " ")
    (attr smd)
    (fp_text reference "C59" (at -0.88 0.41 270) (layer "B.SilkS")
        (effects (font (size 0.7 0.7) (thickness 0.15)) (justify left bottom mirror))
    )
    (fp_text value "C_100n_0402" (at 0 -1.4 270) (layer "B.Fab") hide
        (effects (font (size 0.7 0.7) (thickness 0.15)) (justify left bottom mirror))
    )
    (fp_text user "Author: Antmicro" (at -0.932 -4.17 270) (layer "B.Fab") hide
        (effects (font (size 0.7 0.7) (thickness 0.15)) (justify left bottom mirror))
    )
    (fp_text user "License: Apache-2.0" (at -0.932 -5.17 270) (layer "B.Fab") hide
        (effects (font (size 0.7 0.7) (thickness 0.15)) (justify left bottom mirror))
    )
    (fp_text user "${REFERENCE}" (at -0.932 -3.168 270) (layer "B.Fab") hide
        (effects (font (size 0.7 0.7) (thickness 0.15)) (justify left bottom mirror))
    )
    (fp_rect (start -0.94 0.47) (end 0.94 -0.47)
      (stroke (width 0.05) (type solid)) (fill none) (layer "B.CrtYd"))
    (fp_rect (start -0.499 0.249) (end 0.499 -0.249)
      (stroke (width 0.15) (type solid)) (fill none) (layer "B.Fab"))
    (pad "1" smd roundrect (at -0.484 0 90) (size 0.59 0.64) (layers "B.Cu" "B.Paste" "B.Mask") (roundrect_rratio 0.25)
      (net 15 "PS_3V3") (pintype "passive"))
    (pad "2" smd roundrect (at 0.484 0 90) (size 0.59 0.64) (layers "B.Cu" "B.Paste" "B.Mask") (roundrect_rratio 0.25)
      (net 1 "GND") (pintype "passive"))
  )
	(footprint "kria-k26-devboard-footprints:C_0402_1005Metric" (layer "B.Cu")
    (at 124.1 90 90)
    (descr "Capacitor SMD 0402")
    (tags "capacitor SMD 0402")
    (property "Author" "Antmicro")
    (property "Dielectric" "X5R")
    (property "License" "Apache-2.0")
    (property "MPN" "GRM155R61H104KE14D")
    (property "Manufacturer" "Murata")
    (property "Sheetfile" "usb.kicad_sch")
    (property "Sheetname" "USB")
    (property "Val" "100n")
    (property "Voltage" "50V")
    (property "ki_description" " ")
    (attr smd)
    (fp_text reference "C61" (at -0.84 0.39 270) (layer "B.SilkS")
        (effects (font (size 0.7 0.7) (thickness 0.15)) (justify left bottom mirror))
    )
    (fp_text value "C_100n_0402" (at 0 -1.4 270) (layer "B.Fab") hide
        (effects (font (size 0.7 0.7) (thickness 0.15)) (justify left bottom mirror))
    )
    (fp_text user "Author: Antmicro" (at -0.932 -4.17 270) (layer "B.Fab") hide
        (effects (font (size 0.7 0.7) (thickness 0.15)) (justify left bottom mirror))
    )
    (fp_text user "${REFERENCE}" (at -0.932 -3.168 270) (layer "B.Fab") hide
        (effects (font (size 0.7 0.7) (thickness 0.15)) (justify left bottom mirror))
    )
    (fp_text user "License: Apache-2.0" (at -0.932 -5.17 270) (layer "B.Fab") hide
        (effects (font (size 0.7 0.7) (thickness 0.15)) (justify left bottom mirror))
    )
    (fp_rect (start -0.94 0.47) (end 0.94 -0.47)
      (stroke (width 0.05) (type solid)) (fill none) (layer "B.CrtYd"))
    (fp_rect (start -0.499 0.249) (end 0.499 -0.249)
      (stroke (width 0.15) (type solid)) (fill none) (layer "B.Fab"))
    (pad "1" smd roundrect (at -0.484 0 90) (size 0.59 0.64) (layers "B.Cu" "B.Paste" "B.Mask") (roundrect_rratio 0.25)
      (net 18 "PS_1V2") (pintype "passive"))
    (pad "2" smd roundrect (at 0.484 0 90) (size 0.59 0.64) (layers "B.Cu" "B.Paste" "B.Mask") (roundrect_rratio 0.25)
      (net 1 "GND") (pintype "passive"))
  )
	(footprint "kria-k26-devboard-footprints:R_0402_1005Metric" (layer "B.Cu")
    (at 116.556942 88.4 180)
    (descr "Resistor SMD 0402")
    (tags "resistor SMD 0402")
    (property "Author" "Antmicro")
    (property "License" "Apache-2.0")
    (property "MPN" "CR0402-FX-2003GLF")
    (property "Manufacturer" "Bourns")
    (property "Sheetfile" "usb.kicad_sch")
    (property "Sheetname" "USB")
    (property "Tolerance" "1%")
    (property "Val" "200k")
    (property "ki_description" "200k resistor in 0402 package with 1% tolerance")
    (attr smd)
    (fp_text reference "R43" (at 0.926942 -0.38) (layer "B.SilkS")
        (effects (font (size 0.7 0.7) (thickness 0.15)) (justify left bottom mirror))
    )
    (fp_text value "R_200k_0402" (at 0 -1.4) (layer "B.Fab") hide
        (effects (font (size 0.7 0.7) (thickness 0.15)) (justify left bottom mirror))
    )
    (fp_text user "Author: Antmicro" (at -0.95 -4.169) (layer "B.Fab") hide
        (effects (font (size 0.7 0.7) (thickness 0.15)) (justify left bottom mirror))
    )
    (fp_text user "License: Apache-2.0" (at -0.95 -5.169) (layer "B.Fab") hide
        (effects (font (size 0.7 0.7) (thickness 0.15)) (justify left bottom mirror))
    )
    (fp_text user "${REFERENCE}" (at -0.95 -3.168) (layer "B.Fab") hide
        (effects (font (size 0.7 0.7) (thickness 0.15)) (justify left bottom mirror))
    )
    (fp_rect (start -0.93 0.47) (end 0.93 -0.47)
      (stroke (width 0.05) (type solid)) (fill none) (layer "B.CrtYd"))
    (fp_rect (start -0.5 0.25) (end 0.5 -0.25)
      (stroke (width 0.15) (type solid)) (fill none) (layer "B.Fab"))
    (pad "1" smd roundrect (at -0.485 0 180) (size 0.59 0.64) (layers "B.Cu" "B.Paste" "B.Mask") (roundrect_rratio 0.25)
      (net 1 "GND") (pintype "passive"))
    (pad "2" smd roundrect (at 0.485 0 180) (size 0.59 0.64) (layers "B.Cu" "B.Paste" "B.Mask") (roundrect_rratio 0.25)
      (net 646 "Net-(U17-SPI_D1{slash}PF23)") (pintype "passive"))
  )
)
